(kicad_pcb
	(version 20240108)
	(generator "pcbnew")
	(generator_version "8.0")
	(general
		(thickness 1.62)
		(legacy_teardrops no)
	)
	(paper "A4")
	(title_block
		(title "Jetson Orin Baseboard")
		(date "2025-03-12")
		(rev "1.3.4")
		(company "Antmicro Ltd")
		(comment 1 "www.antmicro.com")
		(comment 9 "footprints 27-31 of 677")
	)
	(layers
		(0 "F.Cu" signal)
		(1 "In1.Cu" signal)
		(2 "In2.Cu" signal)
		(3 "In3.Cu" signal)
		(4 "In4.Cu" jumper)
		(5 "In5.Cu" signal)
		(6 "In6.Cu" signal)
		(31 "B.Cu" signal)
		(32 "B.Adhes" user "B.Adhesive")
		(33 "F.Adhes" user "F.Adhesive")
		(34 "B.Paste" user)
		(35 "F.Paste" user)
		(36 "B.SilkS" user "B.Silkscreen")
		(37 "F.SilkS" user "F.Silkscreen")
		(38 "B.Mask" user)
		(39 "F.Mask" user)
		(40 "Dwgs.User" user "User.Drawings")
		(41 "Cmts.User" user "User.Comments")
		(42 "Eco1.User" user "User.Eco1")
		(43 "Eco2.User" user "User.Eco2")
		(44 "Edge.Cuts" user)
		(45 "Margin" user)
		(46 "B.CrtYd" user "B.Courtyard")
		(47 "F.CrtYd" user "F.Courtyard")
		(48 "B.Fab" user)
		(49 "F.Fab" user)
	)
	(footprint "antmicro-footprints:R_0402_1005Metric"
		(layer "F.Cu")
		(at 75.42 84.34)
		(descr "Resistor SMD 0402")
		(tags "resistor SMD 0402")
		(property "Reference" "R173"
			(at -2.12 -2.3 0)
			(layer "F.SilkS")
			(effects
				(font
					(size 0.7 0.7)
					(thickness 0.15)
				)
				(justify left bottom)
			)
		)
		(property "Value" "R_499k_0402"
			(at -1.011843 1.772047 0)
			(layer "F.Fab")
			(effects
				(font
					(size 0.7 0.7)
					(thickness 0.15)
				)
				(justify left bottom)
			)
		)
		(property "Footprint" "antmicro-footprints:R_0402_1005Metric"
			(at 0 0 0)
			(layer "F.Fab")
			(hide yes)
			(effects
				(font
					(size 1.27 1.27)
					(thickness 0.15)
				)
			)
		)
		(property "Datasheet" "https://www.mouser.com/datasheet/2/54/cr-1858361.pdf"
			(at 0 0 0)
			(layer "F.Fab")
			(hide yes)
			(effects
				(font
					(size 1.27 1.27)
					(thickness 0.15)
				)
			)
		)
		(property "Author" "Antmicro"
			(at 0 0 0)
			(layer "F.Fab")
			(hide yes)
			(effects
				(font
					(size 1 1)
					(thickness 0.15)
				)
			)
		)
		(property "License" "Apache-2.0"
			(at 0 0 0)
			(layer "F.Fab")
			(hide yes)
			(effects
				(font
					(size 1 1)
					(thickness 0.15)
				)
			)
		)
		(property "MPN" "CR0402-FX-4993GLF"
			(at 0 0 0)
			(layer "F.Fab")
			(hide yes)
			(effects
				(font
					(size 1 1)
					(thickness 0.15)
				)
			)
		)
		(property "Manufacturer" "Bourns"
			(at 0 0 0)
			(layer "F.Fab")
			(hide yes)
			(effects
				(font
					(size 1 1)
					(thickness 0.15)
				)
			)
		)
		(property "Tolerance" "1%"
			(at 0 0 0)
			(layer "F.Fab")
			(hide yes)
			(effects
				(font
					(size 1 1)
					(thickness 0.15)
				)
			)
		)
		(property "Val" "499k"
			(at 0 0 0)
			(layer "F.Fab")
			(hide yes)
			(effects
				(font
					(size 1 1)
					(thickness 0.15)
				)
			)
		)
		(sheetname "Supply")
		(sheetfile "supply.kicad_sch")
		(attr smd)
		(fp_rect
			(start -0.925 -0.47)
			(end 0.925 0.47)
			(stroke
				(width 0.05)
				(type default)
			)
			(fill none)
			(layer "F.CrtYd")
		)
		(fp_rect
			(start -0.5 -0.25)
			(end 0.5 0.25)
			(stroke
				(width 0.15)
				(type solid)
			)
			(fill none)
			(layer "F.Fab")
		)
		(fp_text user "Author: Antmicro"
			(at -0.95 4.169 0)
			(layer "F.Fab")
			(hide yes)
			(effects
				(font
					(size 0.7 0.7)
					(thickness 0.15)
				)
				(justify left bottom)
			)
		)
		(fp_text user "${REFERENCE}"
			(at -0.95 3.168 0)
			(layer "F.Fab")
			(hide yes)
			(effects
				(font
					(size 0.7 0.7)
					(thickness 0.15)
				)
				(justify left bottom)
			)
		)
		(fp_text user "License: Apache-2.0"
			(at -0.95 5.169 0)
			(layer "F.Fab")
			(hide yes)
			(effects
				(font
					(size 0.7 0.7)
					(thickness 0.15)
				)
				(justify left bottom)
			)
		)
		(pad "1" smd roundrect
			(at -0.48 0)
			(size 0.59 0.64)
			(layers "F.Cu" "F.Paste" "F.Mask")
			(roundrect_rratio 0.25)
			(net 1 "GND")
			(pintype "passive")
		)
		(pad "2" smd roundrect
			(at 0.48 0)
			(size 0.59 0.64)
			(layers "F.Cu" "F.Paste" "F.Mask")
			(roundrect_rratio 0.25)
			(net 684 "/Supply/3V3_MODE2")
			(pintype "passive")
		)
	)
	(footprint "antmicro-footprints:C_0805_2012Metric"
		(layer "F.Cu")
		(at 62.68 92.95)
		(descr "Capacitor SMD 0805")
		(tags "capacitor SMD 0805")
		(property "Reference" "C152"
			(at 25.62 1.05 0)
			(layer "F.SilkS")
			(effects
				(font
					(size 0.7 0.7)
					(thickness 0.15)
				)
				(justify left bottom)
			)
		)
		(property "Value" "C_22u_25V_0805"
			(at -2.055717 1.963152 0)
			(layer "F.Fab")
			(effects
				(font
					(size 0.7 0.7)
					(thickness 0.15)
				)
				(justify left bottom)
			)
		)
		(property "Footprint" "antmicro-footprints:C_0805_2012Metric"
			(at 0 0 0)
			(layer "F.Fab")
			(hide yes)
			(effects
				(font
					(size 1.27 1.27)
					(thickness 0.15)
				)
			)
		)
		(property "Datasheet" "https://product.samsungsem.com/mlcc/CL21A226MAYNNN.do"
			(at 0 0 0)
			(layer "F.Fab")
			(hide yes)
			(effects
				(font
					(size 1.27 1.27)
					(thickness 0.15)
				)
			)
		)
		(property "Author" "Antmicro"
			(at 0 0 0)
			(layer "F.Fab")
			(hide yes)
			(effects
				(font
					(size 1 1)
					(thickness 0.15)
				)
			)
		)
		(property "Dielectric" "X5R"
			(at 0 0 0)
			(layer "F.Fab")
			(hide yes)
			(effects
				(font
					(size 1 1)
					(thickness 0.15)
				)
			)
		)
		(property "License" "Apache-2.0"
			(at 0 0 0)
			(layer "F.Fab")
			(hide yes)
			(effects
				(font
					(size 1 1)
					(thickness 0.15)
				)
			)
		)
		(property "MPN" "CL21A226MAYNNNE"
			(at 0 0 0)
			(layer "F.Fab")
			(hide yes)
			(effects
				(font
					(size 1 1)
					(thickness 0.15)
				)
			)
		)
		(property "Manufacturer" "Samsung Electro-Mechanics"
			(at 0 0 0)
			(layer "F.Fab")
			(hide yes)
			(effects
				(font
					(size 1 1)
					(thickness 0.15)
				)
			)
		)
		(property "Public" "False"
			(at 0 0 0)
			(layer "F.Fab")
			(hide yes)
			(effects
				(font
					(size 1 1)
					(thickness 0.15)
				)
			)
		)
		(property "Val" "22u"
			(at 0 0 0)
			(layer "F.Fab")
			(hide yes)
			(effects
				(font
					(size 1 1)
					(thickness 0.15)
				)
			)
		)
		(property "Voltage" "25V"
			(at 0 0 0)
			(layer "F.Fab")
			(hide yes)
			(effects
				(font
					(size 1 1)
					(thickness 0.15)
				)
			)
		)
		(sheetname "Supply")
		(sheetfile "supply.kicad_sch")
		(attr smd)
		(fp_line
			(start -0.3 -0.7)
			(end 0.3 -0.7)
			(stroke
				(width 0.15)
				(type solid)
			)
			(layer "F.SilkS")
		)
		(fp_line
			(start -0.3 0.7)
			(end 0.3 0.7)
			(stroke
				(width 0.15)
				(type solid)
			)
			(layer "F.SilkS")
		)
		(fp_rect
			(start 1.95 -0.9)
			(end -1.95 0.9)
			(stroke
				(width 0.05)
				(type default)
			)
			(fill none)
			(layer "F.CrtYd")
		)
		(fp_rect
			(start -0.95 -0.675)
			(end 0.95 0.675)
			(stroke
				(width 0.15)
				(type solid)
			)
			(fill none)
			(layer "F.Fab")
		)
		(fp_text user "License: Apache-2.0"
			(at -1.9 4.947 0)
			(layer "F.Fab")
			(hide yes)
			(effects
				(font
					(size 0.7 0.7)
					(thickness 0.15)
				)
				(justify left bottom)
			)
		)
		(fp_text user "Author: Antmicro"
			(at -1.9 5.947 0)
			(layer "F.Fab")
			(hide yes)
			(effects
				(font
					(size 0.7 0.7)
					(thickness 0.15)
				)
				(justify left bottom)
			)
		)
		(fp_text user "${REFERENCE}"
			(at -1.9 3.947 0)
			(layer "F.Fab")
			(hide yes)
			(effects
				(font
					(size 0.7 0.7)
					(thickness 0.15)
				)
				(justify left bottom)
			)
		)
		(pad "1" smd roundrect
			(at -1.1 0)
			(size 1.2 1.3)
			(layers "F.Cu" "F.Paste" "F.Mask")
			(roundrect_rratio 0.25)
			(net 1 "GND")
			(pintype "passive")
		)
		(pad "2" smd roundrect
			(at 1.1 0)
			(size 1.2 1.3)
			(layers "F.Cu" "F.Paste" "F.Mask")
			(roundrect_rratio 0.25)
			(net 115 "VCC")
			(pintype "passive")
		)
	)
	(footprint "antmicro-footprints:USON-10_2.5x1mm_P0.5mm"
		(layer "F.Cu")
		(at 90.6 119.9 90)
		(descr "USON-10 2.5x1mm_ Pitch 0.5mm")
		(tags "USON-10 2.5x1mm Pitch 0.5mm")
		(property "Reference" "U46"
			(at 0.76 -1.05 0)
			(layer "F.SilkS")
			(effects
				(font
					(size 0.7 0.7)
					(thickness 0.15)
				)
				(justify left bottom)
			)
		)
		(property "Value" "TPD4E05U06QDQARQ1"
			(at 0.018 2.499 90)
			(layer "F.Fab")
			(effects
				(font
					(size 0.7 0.7)
					(thickness 0.15)
				)
				(justify left bottom)
			)
		)
		(property "Footprint" "antmicro-footprints:USON-10_2.5x1mm_P0.5mm"
			(at 0 0 90)
			(layer "F.Fab")
			(hide yes)
			(effects
				(font
					(size 1.27 1.27)
					(thickness 0.15)
				)
			)
		)
		(property "Datasheet" "https://www.ti.com/lit/ds/symlink/tpd4e05u06-q1.pdf?HQS=dis-mous-null-mousermode-dsf-pf-null-wwe&ts=1663591265741&ref_url=https%253A%252F%252Fwww.mouser.com%252F"
			(at 0 0 90)
			(layer "F.Fab")
			(hide yes)
			(effects
				(font
					(size 1.27 1.27)
					(thickness 0.15)
				)
			)
		)
		(property "Author" "Antmicro"
			(at 210.5 29.3 0)
			(layer "F.Fab")
			(hide yes)
			(effects
				(font
					(size 1 1)
					(thickness 0.15)
				)
			)
		)
		(property "License" "Apache-2.0"
			(at 210.5 29.3 0)
			(layer "F.Fab")
			(hide yes)
			(effects
				(font
					(size 1 1)
					(thickness 0.15)
				)
			)
		)
		(property "MPN" "TPD4E05U06QDQARQ1"
			(at 210.5 29.3 0)
			(layer "F.Fab")
			(hide yes)
			(effects
				(font
					(size 1 1)
					(thickness 0.15)
				)
			)
		)
		(property "Manufacturer" "Texas Instruments"
			(at 210.5 29.3 0)
			(layer "F.Fab")
			(hide yes)
			(effects
				(font
					(size 1 1)
					(thickness 0.15)
				)
			)
		)
		(sheetname "HDMI")
		(sheetfile "hdmi.kicad_sch")
		(attr smd)
		(fp_line
			(start 0.498 -1.401)
			(end -0.5 -1.401)
			(stroke
				(width 0.15)
				(type solid)
			)
			(layer "F.SilkS")
		)
		(fp_line
			(start 0.498 1.398)
			(end -0.5 1.398)
			(stroke
				(width 0.15)
				(type solid)
			)
			(layer "F.SilkS")
		)
		(fp_circle
			(center -0.68 -1.27)
			(end -0.63 -1.27)
			(stroke
				(width 0.15)
				(type solid)
			)
			(fill solid)
			(layer "F.SilkS")
		)
		(fp_rect
			(start -0.8 -1.5)
			(end 0.8 1.499)
			(stroke
				(width 0.05)
				(type solid)
			)
			(fill none)
			(layer "F.CrtYd")
		)
		(fp_line
			(start 0.498 -1.25)
			(end -0.25 -1.25)
			(stroke
				(width 0.15)
				(type solid)
			)
			(layer "F.Fab")
		)
		(fp_line
			(start 0.498 -1.25)
			(end 0.498 1.249)
			(stroke
				(width 0.15)
				(type solid)
			)
			(layer "F.Fab")
		)
		(fp_line
			(start -0.25 -1.25)
			(end -0.5 -1)
			(stroke
				(width 0.15)
				(type solid)
			)
			(layer "F.Fab")
		)
		(fp_line
			(start -0.5 -1)
			(end -0.5 1.249)
			(stroke
				(width 0.15)
				(type solid)
			)
			(layer "F.Fab")
		)
		(fp_line
			(start -0.5 1.249)
			(end 0.498 1.249)
			(stroke
				(width 0.15)
				(type solid)
			)
			(layer "F.Fab")
		)
		(fp_text user "License: Apache-2.0"
			(at -0.802 6.9 90)
			(layer "F.Fab")
			(hide yes)
			(effects
				(font
					(size 0.7 0.7)
					(thickness 0.15)
				)
				(justify left bottom)
			)
		)
		(fp_text user "Author: Antmicro"
			(at -0.802 5.7 90)
			(layer "F.Fab")
			(hide yes)
			(effects
				(font
					(size 0.7 0.7)
					(thickness 0.15)
				)
				(justify left bottom)
			)
		)
		(fp_text user "${REFERENCE}"
			(at -0.802 4.498 90)
			(layer "F.Fab")
			(hide yes)
			(effects
				(font
					(size 0.7 0.7)
					(thickness 0.15)
				)
				(justify left bottom)
			)
		)
		(pad "1" smd roundrect
			(at -0.387 -1)
			(size 0.25 0.55)
			(layers "F.Cu" "F.Paste" "F.Mask")
			(roundrect_rratio 0.25)
			(net 529 "/HDMI/HDMI_HPD_5V")
			(pintype "passive")
		)
		(pad "2" smd roundrect
			(at -0.387 -0.5)
			(size 0.25 0.55)
			(layers "F.Cu" "F.Paste" "F.Mask")
			(roundrect_rratio 0.25)
			(net 518 "/HDMI/HDMI_SDA_5V")
			(pintype "passive")
		)
		(pad "3" smd roundrect
			(at -0.387 0)
			(size 0.4 0.55)
			(layers "F.Cu" "F.Paste" "F.Mask")
			(roundrect_rratio 0.25)
			(net 1 "GND")
			(pintype "power_in")
		)
		(pad "4" smd roundrect
			(at -0.387 0.498)
			(size 0.25 0.55)
			(layers "F.Cu" "F.Paste" "F.Mask")
			(roundrect_rratio 0.25)
			(net 519 "/HDMI/HDMI_SCL_5V")
			(pintype "passive")
		)
		(pad "5" smd roundrect
			(at -0.387 0.998)
			(size 0.25 0.55)
			(layers "F.Cu" "F.Paste" "F.Mask")
			(roundrect_rratio 0.25)
			(net 520 "/HDMI/HDMI_CEC_5V")
			(pintype "passive")
		)
		(pad "6" smd roundrect
			(at 0.385 0.998)
			(size 0.25 0.55)
			(layers "F.Cu" "F.Paste" "F.Mask")
			(roundrect_rratio 0.25)
			(net 520 "/HDMI/HDMI_CEC_5V")
			(pintype "passive")
		)
		(pad "7" smd roundrect
			(at 0.385 0.498)
			(size 0.25 0.55)
			(layers "F.Cu" "F.Paste" "F.Mask")
			(roundrect_rratio 0.25)
			(net 519 "/HDMI/HDMI_SCL_5V")
			(pintype "passive")
		)
		(pad "8" smd roundrect
			(at 0.385 0)
			(size 0.4 0.55)
			(layers "F.Cu" "F.Paste" "F.Mask")
			(roundrect_rratio 0.25)
			(net 1 "GND")
			(pintype "passive")
		)
		(pad "9" smd roundrect
			(at 0.385 -0.5)
			(size 0.25 0.55)
			(layers "F.Cu" "F.Paste" "F.Mask")
			(roundrect_rratio 0.25)
			(net 518 "/HDMI/HDMI_SDA_5V")
			(pintype "passive")
		)
		(pad "10" smd roundrect
			(at 0.385 -1)
			(size 0.25 0.55)
			(layers "F.Cu" "F.Paste" "F.Mask")
			(roundrect_rratio 0.25)
			(net 529 "/HDMI/HDMI_HPD_5V")
			(pintype "passive")
		)
	)
	(footprint "antmicro-footprints:R_0402_1005Metric"
		(layer "F.Cu")
		(at 139.1 107.6)
		(descr "Resistor SMD 0402")
		(tags "resistor SMD 0402")
		(property "Reference" "R55"
			(at -3.075 0.1 180)
			(layer "F.SilkS")
			(effects
				(font
					(size 0.7 0.7)
					(thickness 0.15)
				)
				(justify left bottom)
			)
		)
		(property "Value" "R_0R_0402"
			(at 0 1.4 0)
			(layer "F.Fab")
			(effects
				(font
					(size 0.7 0.7)
					(thickness 0.15)
				)
				(justify left bottom)
			)
		)
		(property "Footprint" "antmicro-footprints:R_0402_1005Metric"
			(at 0 0 0)
			(layer "F.Fab")
			(hide yes)
			(effects
				(font
					(size 1.27 1.27)
					(thickness 0.15)
				)
			)
		)
		(property "Datasheet" "https://industrial.panasonic.com/cdbs/www-data/pdf/RDA0000/AOA0000C301.pdf"
			(at 0 0 0)
			(layer "F.Fab")
			(hide yes)
			(effects
				(font
					(size 1.27 1.27)
					(thickness 0.15)
				)
			)
		)
		(property "Author" "Antmicro"
			(at 0 0 0)
			(layer "F.Fab")
			(hide yes)
			(effects
				(font
					(size 1 1)
					(thickness 0.15)
				)
			)
		)
		(property "Current" "1A"
			(at 0 0 0)
			(layer "F.Fab")
			(hide yes)
			(effects
				(font
					(size 1 1)
					(thickness 0.15)
				)
			)
		)
		(property "License" "Apache-2.0"
			(at 0 0 0)
			(layer "F.Fab")
			(hide yes)
			(effects
				(font
					(size 1 1)
					(thickness 0.15)
				)
			)
		)
		(property "MPN" "ERJ2GE0R00X"
			(at 0 0 0)
			(layer "F.Fab")
			(hide yes)
			(effects
				(font
					(size 1 1)
					(thickness 0.15)
				)
			)
		)
		(property "Manufacturer" "Panasonic"
			(at 0 0 0)
			(layer "F.Fab")
			(hide yes)
			(effects
				(font
					(size 1 1)
					(thickness 0.15)
				)
			)
		)
		(property "Tolerance" ""
			(at 0 0 0)
			(layer "F.Fab")
			(hide yes)
			(effects
				(font
					(size 1 1)
					(thickness 0.15)
				)
			)
		)
		(property "Val" "0R"
			(at 0 0 0)
			(layer "F.Fab")
			(hide yes)
			(effects
				(font
					(size 1 1)
					(thickness 0.15)
				)
			)
		)
		(sheetname "Peripherals")
		(sheetfile "peripherals.kicad_sch")
		(attr smd)
		(fp_rect
			(start -0.925 -0.47)
			(end 0.925 0.47)
			(stroke
				(width 0.05)
				(type default)
			)
			(fill none)
			(layer "F.CrtYd")
		)
		(fp_rect
			(start -0.5 -0.25)
			(end 0.5 0.25)
			(stroke
				(width 0.15)
				(type solid)
			)
			(fill none)
			(layer "F.Fab")
		)
		(fp_text user "Author: Antmicro"
			(at -0.95 4.169 0)
			(layer "F.Fab")
			(hide yes)
			(effects
				(font
					(size 0.7 0.7)
					(thickness 0.15)
				)
				(justify left bottom)
			)
		)
		(fp_text user "${REFERENCE}"
			(at -0.95 3.168 0)
			(layer "F.Fab")
			(hide yes)
			(effects
				(font
					(size 0.7 0.7)
					(thickness 0.15)
				)
				(justify left bottom)
			)
		)
		(fp_text user "License: Apache-2.0"
			(at -0.95 5.169 0)
			(layer "F.Fab")
			(hide yes)
			(effects
				(font
					(size 0.7 0.7)
					(thickness 0.15)
				)
				(justify left bottom)
			)
		)
		(pad "1" smd roundrect
			(at -0.48 0)
			(size 0.59 0.64)
			(layers "F.Cu" "F.Paste" "F.Mask")
			(roundrect_rratio 0.25)
			(net 251 "SYS_SDA")
			(pintype "passive")
		)
		(pad "2" smd roundrect
			(at 0.48 0)
			(size 0.59 0.64)
			(layers "F.Cu" "F.Paste" "F.Mask")
			(roundrect_rratio 0.25)
			(net 596 "Net-(J11-Pad63)")
			(pintype "passive")
		)
	)
	(footprint "antmicro-footprints:R_0402_1005Metric"
		(layer "F.Cu")
		(at 99.05 114.65 -90)
		(descr "Resistor SMD 0402")
		(tags "resistor SMD 0402")
		(property "Reference" "R242"
			(at -0.8 -0.45 -90)
			(layer "F.SilkS")
			(effects
				(font
					(size 0.7 0.7)
					(thickness 0.15)
				)
				(justify left bottom)
			)
		)
		(property "Value" "R_10k_0402"
			(at 0 1.4 -90)
			(layer "F.Fab")
			(effects
				(font
					(size 0.7 0.7)
					(thickness 0.15)
				)
				(justify left bottom)
			)
		)
		(property "Footprint" "antmicro-footprints:R_0402_1005Metric"
			(at 0 0 -90)
			(layer "F.Fab")
			(hide yes)
			(effects
				(font
					(size 1.27 1.27)
					(thickness 0.15)
				)
			)
		)
		(property "Datasheet" "https://www.bourns.com/docs/product-datasheets/cr.pdf"
			(at 0 0 -90)
			(layer "F.Fab")
			(hide yes)
			(effects
				(font
					(size 1.27 1.27)
					(thickness 0.15)
				)
			)
		)
		(property "Author" "Antmicro"
			(at -15.6 213.7 0)
			(layer "F.Fab")
			(hide yes)
			(effects
				(font
					(size 1 1)
					(thickness 0.15)
				)
			)
		)
		(property "License" "Apache-2.0"
			(at -15.6 213.7 0)
			(layer "F.Fab")
			(hide yes)
			(effects
				(font
					(size 1 1)
					(thickness 0.15)
				)
			)
		)
		(property "MPN" "CR0402-FX-1002GLF"
			(at -15.6 213.7 0)
			(layer "F.Fab")
			(hide yes)
			(effects
				(font
					(size 1 1)
					(thickness 0.15)
				)
			)
		)
		(property "Manufacturer" "Bourns"
			(at -15.6 213.7 0)
			(layer "F.Fab")
			(hide yes)
			(effects
				(font
					(size 1 1)
					(thickness 0.15)
				)
			)
		)
		(property "Tolerance" "1%"
			(at -15.6 213.7 0)
			(layer "F.Fab")
			(hide yes)
			(effects
				(font
					(size 1 1)
					(thickness 0.15)
				)
			)
		)
		(property "Val" "10k"
			(at -15.6 213.7 0)
			(layer "F.Fab")
			(hide yes)
			(effects
				(font
					(size 1 1)
					(thickness 0.15)
				)
			)
		)
		(sheetname "Peripherals")
		(sheetfile "peripherals.kicad_sch")
		(attr smd)
		(fp_rect
			(start -0.925 -0.47)
			(end 0.925 0.47)
			(stroke
				(width 0.05)
				(type default)
			)
			(fill none)
			(layer "F.CrtYd")
		)
		(fp_rect
			(start -0.5 -0.25)
			(end 0.5 0.25)
			(stroke
				(width 0.15)
				(type solid)
			)
			(fill none)
			(layer "F.Fab")
		)
		(fp_text user "License: Apache-2.0"
			(at -0.95 5.169 -90)
			(layer "F.Fab")
			(hide yes)
			(effects
				(font
					(size 0.7 0.7)
					(thickness 0.15)
				)
				(justify left bottom)
			)
		)
		(fp_text user "Author: Antmicro"
			(at -0.95 4.169 -90)
			(layer "F.Fab")
			(hide yes)
			(effects
				(font
					(size 0.7 0.7)
					(thickness 0.15)
				)
				(justify left bottom)
			)
		)
		(fp_text user "${REFERENCE}"
			(at -0.95 3.168 -90)
			(layer "F.Fab")
			(hide yes)
			(effects
				(font
					(size 0.7 0.7)
					(thickness 0.15)
				)
				(justify left bottom)
			)
		)
		(pad "1" smd roundrect
			(at -0.48 0 270)
			(size 0.59 0.64)
			(layers "F.Cu" "F.Paste" "F.Mask")
			(roundrect_rratio 0.25)
			(net 46 "USER_BTN1")
			(pintype "passive")
		)
		(pad "2" smd roundrect
			(at 0.48 0 270)
			(size 0.59 0.64)
			(layers "F.Cu" "F.Paste" "F.Mask")
			(roundrect_rratio 0.25)
			(net 112 "+1V8")
			(pintype "passive")
		)
	)
)
